(kicad_pcb
	(version 20211014)
	(generator pcbnew)
	(general
    (thickness 1.6)
  )
	(paper "A4")
	(title_block
    (title "SA800U (Snapdragon 845) Baseboard")
    (date "2023-10-19")
    (rev "1.0.3")
    (company "Antmicro Ltd.")
    (comment 1 "www.antmicro.com")
		(comment 9 "footprint 58 of 589 (U11), pads 195-289 of 348")
	)
	(layers
    (0 "F.Cu" signal)
    (1 "In1.Cu" power)
    (2 "In2.Cu" signal)
    (3 "In3.Cu" signal)
    (4 "In4.Cu" power)
    (31 "B.Cu" signal)
    (32 "B.Adhes" user "B.Adhesive")
    (33 "F.Adhes" user "F.Adhesive")
    (34 "B.Paste" user)
    (35 "F.Paste" user)
    (36 "B.SilkS" user "B.Silkscreen")
    (37 "F.SilkS" user "F.Silkscreen")
    (38 "B.Mask" user)
    (39 "F.Mask" user)
    (40 "Dwgs.User" user "User.Drawings")
    (41 "Cmts.User" user "User.Comments")
    (42 "Eco1.User" user "User.Eco1")
    (43 "Eco2.User" user "User.Eco2")
    (44 "Edge.Cuts" user)
    (45 "Margin" user)
    (46 "B.CrtYd" user "B.Courtyard")
    (47 "F.CrtYd" user "F.Courtyard")
    (48 "B.Fab" user)
    (49 "F.Fab" user)
  )
	(footprint "sa800u-baseboard-hw-footprints:Receptacle_SA800U-WF" locked
    (layer "F.Cu")
    (tedit 6215E1EF)
    (at 112.47 100.96)
    (property "Author" "Antmicro")
    (property "License" "Apache-2.0")
    (property "MPN" "FX10A-168S-SV")
    (property "Manufacturer" "Hirose Electric")
    (property "Sheetfile" "som.kicad_sch")
    (property "Sheetname" "SoM")
    (attr smd)
    (fp_text reference "U11" (at 0.005 -19.31) (layer "F.SilkS")
      (effects (font (size 0.7 0.7) (thickness 0.15)) (justify left bottom))
    )
    (fp_text value "Receptacle_SA800U-WF" (at 0 20.4) (layer "F.Fab")
      (effects (font (size 0.7 0.7) (thickness 0.15)) (justify left bottom))
    )
    (pad "2_17" smd rect locked (at 15.761 17.573 180) (size 0.33 1.6) (layers "F.Cu" "F.Paste" "F.Mask")
      (net 1 "GND") (pinfunction "GND") (pintype "passive"))
    (pad "2_18" smd rect locked (at 15.761 11.473 180) (size 0.33 1.6) (layers "F.Cu" "F.Paste" "F.Mask")
      (net 1 "GND") (pinfunction "GND") (pintype "passive"))
    (pad "2_19" smd rect locked (at 15.261 17.573 180) (size 0.33 1.6) (layers "F.Cu" "F.Paste" "F.Mask")
      (net 56 "DSI1_CLK_P") (pinfunction "DSI1_CLK_P") (pintype "output"))
    (pad "2_20" smd rect locked (at 15.261 11.473 180) (size 0.33 1.6) (layers "F.Cu" "F.Paste" "F.Mask")
      (net 91 "DSI0_LN2_N") (pinfunction "DSI0_LN2_N") (pintype "output"))
    (pad "2_21" smd rect locked (at 14.761 17.573 180) (size 0.33 1.6) (layers "F.Cu" "F.Paste" "F.Mask")
      (net 55 "DSI1_CLK_N") (pinfunction "DSI1_CLK_N") (pintype "output"))
    (pad "2_22" smd rect locked (at 14.761 11.473 180) (size 0.33 1.6) (layers "F.Cu" "F.Paste" "F.Mask")
      (net 92 "DSI0_LN2_P") (pinfunction "DSI0_LN2_P") (pintype "output"))
    (pad "2_23" smd rect locked (at 14.261 17.573 180) (size 0.33 1.6) (layers "F.Cu" "F.Paste" "F.Mask")
      (net 1 "GND") (pinfunction "GND") (pintype "passive"))
    (pad "2_24" smd rect locked (at 14.261 11.473 180) (size 0.33 1.6) (layers "F.Cu" "F.Paste" "F.Mask")
      (net 1 "GND") (pinfunction "GND") (pintype "passive"))
    (pad "2_25" smd rect locked (at 13.761 17.573 180) (size 0.33 1.6) (layers "F.Cu" "F.Paste" "F.Mask")
      (net 57 "DSI1_LN2_P") (pinfunction "DSI1_LN2_P") (pintype "output"))
    (pad "2_26" smd rect locked (at 13.761 11.473 180) (size 0.33 1.6) (layers "F.Cu" "F.Paste" "F.Mask")
      (net 86 "DSI0_CLK_N") (pinfunction "DSI0_CLK_N") (pintype "output"))
    (pad "2_27" smd rect locked (at 13.261 17.573 180) (size 0.33 1.6) (layers "F.Cu" "F.Paste" "F.Mask")
      (net 53 "DSI1_LN2_N") (pinfunction "DSI1_LN2_N") (pintype "output"))
    (pad "2_28" smd rect locked (at 13.261 11.473 180) (size 0.33 1.6) (layers "F.Cu" "F.Paste" "F.Mask")
      (net 85 "DSI0_CLK_P") (pinfunction "DSI0_CLK_P") (pintype "output"))
    (pad "2_29" smd rect locked (at 12.761 17.573 180) (size 0.33 1.6) (layers "F.Cu" "F.Paste" "F.Mask")
      (net 1 "GND") (pinfunction "GND") (pintype "passive"))
    (pad "2_30" smd rect locked (at 12.761 11.473 180) (size 0.33 1.6) (layers "F.Cu" "F.Paste" "F.Mask")
      (net 1 "GND") (pinfunction "GND") (pintype "passive"))
    (pad "2_31" smd rect locked (at 12.261 17.573 180) (size 0.33 1.6) (layers "F.Cu" "F.Paste" "F.Mask")
      (net 54 "DSI1_LN3_N") (pinfunction "DSI1_LN3_N") (pintype "output"))
    (pad "2_32" smd rect locked (at 12.261 11.473 180) (size 0.33 1.6) (layers "F.Cu" "F.Paste" "F.Mask")
      (net 83 "DSI0_LN1_N") (pinfunction "DSI0_LN1_N") (pintype "output"))
    (pad "2_33" smd rect locked (at 11.761 17.573 180) (size 0.33 1.6) (layers "F.Cu" "F.Paste" "F.Mask")
      (net 58 "DSI1_LN3_P") (pinfunction "DSI1_LN3_P") (pintype "output"))
    (pad "2_34" smd rect locked (at 11.761 11.473 180) (size 0.33 1.6) (layers "F.Cu" "F.Paste" "F.Mask")
      (net 84 "DSI0_LN1_P") (pinfunction "DSI0_LN1_P") (pintype "output"))
    (pad "2_35" smd rect locked (at 11.261 17.573 180) (size 0.33 1.6) (layers "F.Cu" "F.Paste" "F.Mask")
      (net 1 "GND") (pinfunction "GND") (pintype "passive"))
    (pad "2_36" smd rect locked (at 11.261 11.473 180) (size 0.33 1.6) (layers "F.Cu" "F.Paste" "F.Mask")
      (net 1 "GND") (pinfunction "GND") (pintype "passive"))
    (pad "2_37" smd rect locked (at 10.761 17.573 180) (size 0.33 1.6) (layers "F.Cu" "F.Paste" "F.Mask")
      (net 52 "DSI1_LN1_N") (pinfunction "DSI1_LN1_N") (pintype "output"))
    (pad "2_38" smd rect locked (at 10.761 11.473 180) (size 0.33 1.6) (layers "F.Cu" "F.Paste" "F.Mask")
      (net 87 "DSI0_LN0_N") (pinfunction "DSI0_LN0_N") (pintype "output"))
    (pad "2_39" smd rect locked (at 10.261 17.573 180) (size 0.33 1.6) (layers "F.Cu" "F.Paste" "F.Mask")
      (net 50 "DSI1_LN1_P") (pinfunction "DSI1_LN1_P") (pintype "output"))
    (pad "2_40" smd rect locked (at 10.261 11.473 180) (size 0.33 1.6) (layers "F.Cu" "F.Paste" "F.Mask")
      (net 88 "DSI0_LN0_P") (pinfunction "DSI0_LN0_P") (pintype "output"))
    (pad "2_41" smd rect locked (at 9.761 17.573 180) (size 0.33 1.6) (layers "F.Cu" "F.Paste" "F.Mask")
      (net 1 "GND") (pinfunction "GND") (pintype "passive"))
    (pad "2_42" smd rect locked (at 9.761 11.473 180) (size 0.33 1.6) (layers "F.Cu" "F.Paste" "F.Mask")
      (net 1 "GND") (pinfunction "GND") (pintype "passive"))
    (pad "2_43" smd rect locked (at 9.261 17.573 180) (size 0.33 1.6) (layers "F.Cu" "F.Paste" "F.Mask")
      (net 560 "/SoM/WCD_CLK") (pinfunction "WCD_CLK") (pintype "output+no_connect"))
    (pad "2_44" smd rect locked (at 9.261 11.473 180) (size 0.33 1.6) (layers "F.Cu" "F.Paste" "F.Mask")
      (net 81 "TP_I2C_SCL") (pinfunction "TP_I2C_SCL") (pintype "output"))
    (pad "2_45" smd rect locked (at 8.761 17.573 180) (size 0.33 1.6) (layers "F.Cu" "F.Paste" "F.Mask")
      (net 1 "GND") (pinfunction "GND") (pintype "passive"))
    (pad "2_46" smd rect locked (at 8.761 11.473 180) (size 0.33 1.6) (layers "F.Cu" "F.Paste" "F.Mask")
      (net 82 "TP_I2C_SDA") (pinfunction "TP_I2C_SDA") (pintype "bidirectional"))
    (pad "2_47" smd rect locked (at 8.261 17.573 180) (size 0.33 1.6) (layers "F.Cu" "F.Paste" "F.Mask")
      (net 559 "/SoM/SLIMBUS_DATA0") (pinfunction "SLIMBUS_DATA0") (pintype "bidirectional+no_connect"))
    (pad "2_48" smd rect locked (at 8.261 11.473 180) (size 0.33 1.6) (layers "F.Cu" "F.Paste" "F.Mask")
      (net 558 "/SoM/TP_INT") (pinfunction "TP_INT") (pintype "input+no_connect"))
    (pad "2_49" smd rect locked (at 7.76 17.573 180) (size 0.33 1.6) (layers "F.Cu" "F.Paste" "F.Mask")
      (net 557 "/SoM/SLIMBUS_DATA1") (pinfunction "SLIMBUS_DATA1") (pintype "bidirectional+no_connect"))
    (pad "2_50" smd rect locked (at 7.76 11.473 180) (size 0.33 1.6) (layers "F.Cu" "F.Paste" "F.Mask")
      (net 556 "/SoM/TP_RST") (pinfunction "TP_RST") (pintype "output+no_connect"))
    (pad "2_51" smd rect locked (at 7.26 17.573 180) (size 0.33 1.6) (layers "F.Cu" "F.Paste" "F.Mask")
      (net 555 "/SoM/SLIMBUS_CLK") (pinfunction "SLIMBUS_CLK") (pintype "output+no_connect"))
    (pad "2_52" smd rect locked (at 7.26 11.473 180) (size 0.33 1.6) (layers "F.Cu" "F.Paste" "F.Mask")
      (net 554 "unconnected-(U11-Pad2_52)") (pinfunction "SPI2_CLK") (pintype "output+no_connect"))
    (pad "2_53" smd rect locked (at 6.76 17.573 180) (size 0.33 1.6) (layers "F.Cu" "F.Paste" "F.Mask")
      (net 1 "GND") (pinfunction "GND") (pintype "passive"))
    (pad "2_54" smd rect locked (at 6.76 11.473 180) (size 0.33 1.6) (layers "F.Cu" "F.Paste" "F.Mask")
      (net 101 "USB2_EN") (pinfunction "SPI2_CS") (pintype "output"))
    (pad "2_55" smd rect locked (at 6.26 17.573 180) (size 0.33 1.6) (layers "F.Cu" "F.Paste" "F.Mask")
      (net 553 "/SoM/I2S2_WS") (pinfunction "I2S2_WS") (pintype "output+no_connect"))
    (pad "2_56" smd rect locked (at 6.26 11.473 180) (size 0.33 1.6) (layers "F.Cu" "F.Paste" "F.Mask")
      (net 552 "unconnected-(U11-Pad2_56)") (pinfunction "SPI2_MISO") (pintype "input+no_connect"))
    (pad "2_57" smd rect locked (at 5.761 17.573 180) (size 0.33 1.6) (layers "F.Cu" "F.Paste" "F.Mask")
      (net 551 "/SoM/I2S2_SCK") (pinfunction "I2S2_SCK") (pintype "output+no_connect"))
    (pad "2_58" smd rect locked (at 5.761 11.473 180) (size 0.33 1.6) (layers "F.Cu" "F.Paste" "F.Mask")
      (net 550 "unconnected-(U11-Pad2_58)") (pinfunction "SPI2_MOSI") (pintype "output+no_connect"))
    (pad "2_59" smd rect locked (at 5.261 17.573 180) (size 0.33 1.6) (layers "F.Cu" "F.Paste" "F.Mask")
      (net 549 "/SoM/I2S2_DATA0") (pinfunction "I2S2_DATA0") (pintype "bidirectional+no_connect"))
    (pad "2_60" smd rect locked (at 5.261 11.473 180) (size 0.33 1.6) (layers "F.Cu" "F.Paste" "F.Mask")
      (net 548 "unconnected-(U11-Pad2_60)") (pinfunction "LCD_TE") (pintype "input+no_connect"))
    (pad "2_61" smd rect locked (at 4.761 17.573 180) (size 0.33 1.6) (layers "F.Cu" "F.Paste" "F.Mask")
      (net 547 "/SoM/I2S2_DATA1") (pinfunction "I2S2_DATA1") (pintype "bidirectional+no_connect"))
    (pad "2_62" smd rect locked (at 4.761 11.473 180) (size 0.33 1.6) (layers "F.Cu" "F.Paste" "F.Mask")
      (net 546 "unconnected-(U11-Pad2_62)") (pinfunction "LCD_RST") (pintype "output+no_connect"))
    (pad "2_63" smd rect locked (at 4.261 17.573 180) (size 0.33 1.6) (layers "F.Cu" "F.Paste" "F.Mask")
      (net 545 "/SoM/I2S3_WS") (pinfunction "I2S3_WS") (pintype "output+no_connect"))
    (pad "2_64" smd rect locked (at 4.261 11.473 180) (size 0.33 1.6) (layers "F.Cu" "F.Paste" "F.Mask")
      (net 168 "STUSB4500_ALERT") (pinfunction "GPIO_42") (pintype "bidirectional"))
    (pad "2_65" smd rect locked (at 3.761 17.573 180) (size 0.33 1.6) (layers "F.Cu" "F.Paste" "F.Mask")
      (net 544 "unconnected-(U11-Pad2_65)") (pinfunction "I2S3_DATA1") (pintype "bidirectional+no_connect"))
    (pad "2_66" smd rect locked (at 3.761 11.473 180) (size 0.33 1.6) (layers "F.Cu" "F.Paste" "F.Mask")
      (net 165 "STUSB4500_AB_SIDE") (pinfunction "GPIO_44") (pintype "bidirectional"))
    (pad "2_67" smd rect locked (at 3.261 17.573 180) (size 0.33 1.6) (layers "F.Cu" "F.Paste" "F.Mask")
      (net 543 "unconnected-(U11-Pad2_67)") (pinfunction "I2S3_DATA2") (pintype "bidirectional+no_connect"))
    (pad "2_68" smd rect locked (at 3.261 11.473 180) (size 0.33 1.6) (layers "F.Cu" "F.Paste" "F.Mask")
      (net 35 "LT9611_GPIO5") (pinfunction "GPIO_52") (pintype "bidirectional"))
    (pad "2_69" smd rect locked (at 2.761 17.573 180) (size 0.33 1.6) (layers "F.Cu" "F.Paste" "F.Mask")
      (net 542 "/SoM/I2S3_DATA0") (pinfunction "I2S3_DATA0") (pintype "bidirectional+no_connect"))
    (pad "2_70" smd rect locked (at 2.761 11.473 180) (size 0.33 1.6) (layers "F.Cu" "F.Paste" "F.Mask")
      (net 36 "LT9611_RST") (pinfunction "GPIO_50") (pintype "bidirectional"))
    (pad "2_71" smd rect locked (at 2.261 17.573 180) (size 0.33 1.6) (layers "F.Cu" "F.Paste" "F.Mask")
      (net 541 "unconnected-(U11-Pad2_71)") (pinfunction "I2S3_DATA3") (pintype "bidirectional+no_connect"))
    (pad "2_72" smd rect locked (at 2.261 11.473 180) (size 0.33 1.6) (layers "F.Cu" "F.Paste" "F.Mask")
      (net 166 "STUSB4500_GPIO") (pinfunction "GPIO_134") (pintype "bidirectional"))
    (pad "2_73" smd rect locked (at 1.761 17.573 180) (size 0.33 1.6) (layers "F.Cu" "F.Paste" "F.Mask")
      (net 540 "/SoM/I2S3_SCK") (pinfunction "I2S3_SCK") (pintype "output+no_connect"))
    (pad "2_74" smd rect locked (at 1.761 11.473 180) (size 0.33 1.6) (layers "F.Cu" "F.Paste" "F.Mask")
      (net 167 "STUSB4500_ATTACH") (pinfunction "GPIO_122") (pintype "bidirectional"))
    (pad "2_75" smd rect locked (at 1.261 17.573 180) (size 0.33 1.6) (layers "F.Cu" "F.Paste" "F.Mask")
      (net 150 "I2C10_SCL") (pinfunction "I2C10_SCL") (pintype "output"))
    (pad "2_76" smd rect locked (at 1.261 11.473 180) (size 0.33 1.6) (layers "F.Cu" "F.Paste" "F.Mask")
      (net 351 "USB_PD_DISABLE") (pinfunction "GPIO_124") (pintype "bidirectional"))
    (pad "2_77" smd rect locked (at 0.76 17.573 180) (size 0.33 1.6) (layers "F.Cu" "F.Paste" "F.Mask")
      (net 151 "I2C10_SDA") (pinfunction "I2C10_SDA") (pintype "bidirectional"))
    (pad "2_78" smd rect locked (at 0.76 11.473 180) (size 0.33 1.6) (layers "F.Cu" "F.Paste" "F.Mask")
      (net 539 "unconnected-(U11-Pad2_78)") (pinfunction "GPIO_49") (pintype "bidirectional+no_connect"))
    (pad "2_79" smd rect locked (at 0.261 17.573 180) (size 0.33 1.6) (layers "F.Cu" "F.Paste" "F.Mask")
      (net 59 "I2S1_WS") (pinfunction "I2S1_WS") (pintype "output"))
    (pad "2_80" smd rect locked (at 0.261 11.473 180) (size 0.33 1.6) (layers "F.Cu" "F.Paste" "F.Mask")
      (net 99 "USB2_SINK") (pinfunction "SPI0_CS") (pintype "output"))
    (pad "2_81" smd rect locked (at -0.24 17.573 180) (size 0.33 1.6) (layers "F.Cu" "F.Paste" "F.Mask")
      (net 60 "I2S1_MCLK") (pinfunction "I2S1_MCLK") (pintype "output"))
    (pad "2_82" smd rect locked (at -0.24 11.473 180) (size 0.33 1.6) (layers "F.Cu" "F.Paste" "F.Mask")
      (net 538 "unconnected-(U11-Pad2_82)") (pinfunction "SPI0_MOSI") (pintype "output+no_connect"))
    (pad "2_83" smd rect locked (at -0.739 17.573 180) (size 0.33 1.6) (layers "F.Cu" "F.Paste" "F.Mask")
      (net 61 "I2S1_SCK") (pinfunction "I2S1_SCK") (pintype "output"))
    (pad "2_84" smd rect locked (at -0.739 11.473 180) (size 0.33 1.6) (layers "F.Cu" "F.Paste" "F.Mask")
      (net 537 "unconnected-(U11-Pad2_84)") (pinfunction "SPI0_MISO") (pintype "input+no_connect"))
    (pad "2_85" smd rect locked (at -1.24 17.573 180) (size 0.33 1.6) (layers "F.Cu" "F.Paste" "F.Mask")
      (net 536 "unconnected-(U11-Pad2_85)") (pinfunction "I2S1_DATA1") (pintype "bidirectional+no_connect"))
    (pad "2_86" smd rect locked (at -1.24 11.473 180) (size 0.33 1.6) (layers "F.Cu" "F.Paste" "F.Mask")
      (net 535 "unconnected-(U11-Pad2_86)") (pinfunction "SPI0_CLK") (pintype "output+no_connect"))
    (pad "2_87" smd rect locked (at -1.74 17.573 180) (size 0.33 1.6) (layers "F.Cu" "F.Paste" "F.Mask")
      (net 62 "I2S1_DATA0") (pinfunction "I2S1_DATA0") (pintype "bidirectional"))
    (pad "2_88" smd rect locked (at -1.74 11.473 180) (size 0.33 1.6) (layers "F.Cu" "F.Paste" "F.Mask")
      (net 534 "unconnected-(U11-Pad2_88)") (pinfunction "RESERVED2") (pintype "no_connect"))
    (pad "2_89" smd rect locked (at -2.239 17.573 180) (size 0.33 1.6) (layers "F.Cu" "F.Paste" "F.Mask")
      (net 533 "/SoM/CODEC_SPI_MISO") (pinfunction "CODEC_SPI_MISO") (pintype "input+no_connect"))
    (pad "2_90" smd rect locked (at -2.239 11.473 180) (size 0.33 1.6) (layers "F.Cu" "F.Paste" "F.Mask")
      (net 532 "unconnected-(U11-Pad2_90)") (pinfunction "CODEC_RST") (pintype "output+no_connect"))
    (pad "2_91" smd rect locked (at -2.741 17.573 180) (size 0.33 1.6) (layers "F.Cu" "F.Paste" "F.Mask")
      (net 531 "/SoM/CODEC_INT1") (pinfunction "CODEC_INT1") (pintype "input+no_connect"))
    (pad "2_92" smd rect locked (at -2.741 11.473 180) (size 0.33 1.6) (layers "F.Cu" "F.Paste" "F.Mask")
      (net 530 "unconnected-(U11-Pad2_92)") (pinfunction "CODEC_SPI_CLK") (pintype "output+no_connect"))
    (pad "2_93" smd rect locked (at -3.241 17.573 180) (size 0.33 1.6) (layers "F.Cu" "F.Paste" "F.Mask")
      (net 529 "/SoM/CODEC_INT2") (pinfunction "CODEC_INT2") (pintype "input+no_connect"))
    (pad "2_94" smd rect locked (at -3.241 11.473 180) (size 0.33 1.6) (layers "F.Cu" "F.Paste" "F.Mask")
      (net 528 "unconnected-(U11-Pad2_94)") (pinfunction "CODEC_SPI_MOSI") (pintype "output+no_connect"))
    (pad "2_95" smd rect locked (at -3.741 17.573 180) (size 0.33 1.6) (layers "F.Cu" "F.Paste" "F.Mask")
      (net 527 "/SoM/CAM3_TRIGGER_IN") (pinfunction "SPI11_MOSI") (pintype "output+no_connect"))
    (pad "2_96" smd rect locked (at -3.741 11.473 180) (size 0.33 1.6) (layers "F.Cu" "F.Paste" "F.Mask")
      (net 526 "unconnected-(U11-Pad2_96)") (pinfunction "CODEC_SPI_CS") (pintype "output+no_connect"))
    (pad "2_97" smd rect locked (at -4.241 17.573 180) (size 0.33 1.6) (layers "F.Cu" "F.Paste" "F.Mask")
      (net 525 "/SoM/ETH_3V3_EN") (pinfunction "SPI11_MISO") (pintype "input+no_connect"))
    (pad "2_98" smd rect locked (at -4.241 11.473 180) (size 0.33 1.6) (layers "F.Cu" "F.Paste" "F.Mask")
      (net 1 "GND") (pinfunction "GND") (pintype "passive"))
    (pad "2_99" smd rect locked (at -4.741 17.573 180) (size 0.33 1.6) (layers "F.Cu" "F.Paste" "F.Mask")
      (net 524 "unconnected-(U11-Pad2_99)") (pinfunction "SPI11_CLK") (pintype "output+no_connect"))
    (pad "2_100" smd rect locked (at -4.741 11.473 180) (size 0.33 1.6) (layers "F.Cu" "F.Paste" "F.Mask")
      (net 104 "USB2_SS_RX_N") (pinfunction "USB2_SS_RX_M") (pintype "input"))
    (pad "2_101" smd rect locked (at -5.241 17.573 180) (size 0.33 1.6) (layers "F.Cu" "F.Paste" "F.Mask")
      (net 523 "unconnected-(U11-Pad2_101)") (pinfunction "SPI11_CS") (pintype "output+no_connect"))
    (pad "2_102" smd rect locked (at -5.241 11.473 180) (size 0.33 1.6) (layers "F.Cu" "F.Paste" "F.Mask")
      (net 105 "USB2_SS_RX_P") (pinfunction "USB2_SS_RX_P") (pintype "input"))
    (pad "2_103" smd rect locked (at -5.741 17.573 180) (size 0.33 1.6) (layers "F.Cu" "F.Paste" "F.Mask")
      (net 1 "GND") (pinfunction "GND") (pintype "power_in"))
    (pad "2_104" smd rect locked (at -5.741 11.473 180) (size 0.33 1.6) (layers "F.Cu" "F.Paste" "F.Mask")
      (net 1 "GND") (pinfunction "GND") (pintype "passive"))
    (pad "2_105" smd rect locked (at -6.241 17.573 180) (size 0.33 1.6) (layers "F.Cu" "F.Paste" "F.Mask")
      (net 80 "USB2C_HS_D_P") (pinfunction "USB2_DP") (pintype "bidirectional"))
    (pad "2_106" smd rect locked (at -6.241 11.473 180) (size 0.33 1.6) (layers "F.Cu" "F.Paste" "F.Mask")
      (net 103 "USB2_SS_TX_P") (pinfunction "USB2_SS_TX_P") (pintype "output"))
    (pad "2_107" smd rect locked (at -6.741 17.573 180) (size 0.33 1.6) (layers "F.Cu" "F.Paste" "F.Mask")
      (net 79 "USB2C_HS_D_N") (pinfunction "USB2_DM") (pintype "bidirectional"))
    (pad "2_108" smd rect locked (at -6.741 11.473 180) (size 0.33 1.6) (layers "F.Cu" "F.Paste" "F.Mask")
      (net 102 "USB2_SS_TX_N") (pinfunction "USB2_SS_TX_M") (pintype "output"))
    (pad "2_109" smd rect locked (at -7.241 17.573 180) (size 0.33 1.6) (layers "F.Cu" "F.Paste" "F.Mask")
      (net 1 "GND") (pinfunction "GND") (pintype "passive"))
    (pad "2_110" smd rect locked (at -7.241 11.473 180) (size 0.33 1.6) (layers "F.Cu" "F.Paste" "F.Mask")
      (net 1 "GND") (pinfunction "GND") (pintype "passive"))
    (pad "2_111" smd rect locked (at -7.741 17.573 180) (size 0.33 1.6) (layers "F.Cu" "F.Paste" "F.Mask")
      (net 71 "USB1_SS_TX1_N") (pinfunction "USB1_SS2_TX_M") (pintype "output"))
  )
)
